(kicad_pcb
	(version 20260206)
	(generator "pcbnew")
	(generator_version "10.0")
	(general
		(thickness 1.6)
		(legacy_teardrops no)
	)
	(paper "A4")
	(title_block
		(title "01162023_DA0F0TEBIF0_F0T_Expander_BD_F_brd_V02_OCP.brd")
		(comment 1 "Grand Teton / footprints 8502-8506 of 9728")
	)
	(layers
		(0 "F.Cu" signal "TOP")
		(4 "In1.Cu" signal "GND")
		(6 "In2.Cu" signal "VCC")
		(8 "In3.Cu" signal "VCC1")
		(10 "In4.Cu" signal "GND1")
		(12 "In5.Cu" signal "IN1")
		(14 "In6.Cu" signal "GND2")
		(16 "In7.Cu" signal "IN2")
		(18 "In8.Cu" signal "GND3")
		(20 "In9.Cu" signal "IN3")
		(22 "In10.Cu" signal "GND4")
		(24 "In11.Cu" signal "IN4")
		(26 "In12.Cu" signal "GND5")
		(28 "In13.Cu" signal "IN5")
		(30 "In14.Cu" signal "GND6")
		(32 "In15.Cu" signal "IN6")
		(34 "In16.Cu" signal "GND7")
		(2 "B.Cu" signal "BOTTOM")
		(9 "F.Adhes" user "F.Adhesive")
		(11 "B.Adhes" user "B.Adhesive")
		(13 "F.Paste" user "Package Geometry/Pastemask Top")
		(15 "B.Paste" user "Package Geometry/Pastemask Bottom")
		(5 "F.SilkS" user "Ref Des/Silkscreen Top")
		(7 "B.SilkS" user "Ref Des/Silkscreen Bottom")
		(1 "F.Mask" user "Board Geometry/Soldermask Top")
		(3 "B.Mask" user "Board Geometry/Soldermask Bottom")
		(17 "Dwgs.User" user "User.Drawings")
		(19 "Cmts.User" user "User.Comments")
		(21 "Eco1.User" user "User.Eco1")
		(23 "Eco2.User" user "User.Eco2")
		(25 "Edge.Cuts" user "Board Geometry/Outline")
		(27 "Margin" user)
		(31 "F.CrtYd" user "Package Geometry/Place Bound Top")
		(29 "B.CrtYd" user "Package Geometry/Place Bound Bottom")
		(35 "F.Fab" user "Ref Des/Assembly Top")
		(33 "B.Fab" user "Ref Des/Assembly Bottom")
	)
	(footprint ""
		(layer "B.Cu")
		(at 347.2688 -361.4166)
		(property "Reference" "C4128"
			(at 0 0 0)
			(layer "B.SilkS")
			(hide yes)
			(effects
				(font
					(size 1.27 1.27)
				)
				(justify mirror)
			)
		)
		(property "Value" ""
			(at 0 0 0)
			(layer "B.Fab")
			(effects
				(font
					(size 1.27 1.27)
				)
				(justify mirror)
			)
		)
		(duplicate_pad_numbers_are_jumpers no)
		(fp_line
			(start -0.7874 -0.4064)
			(end -0.7874 0.4064)
			(stroke
				(width 0.1524)
				(type default)
			)
			(layer "B.SilkS")
		)
		(fp_line
			(start -0.7874 0.4064)
			(end 0.7874 0.4064)
			(stroke
				(width 0.1524)
				(type default)
			)
			(layer "B.SilkS")
		)
		(fp_line
			(start 0.7874 -0.4064)
			(end -0.7874 -0.4064)
			(stroke
				(width 0.1524)
				(type default)
			)
			(layer "B.SilkS")
		)
		(fp_line
			(start 0.7874 0.4064)
			(end 0.7874 -0.4064)
			(stroke
				(width 0.1524)
				(type default)
			)
			(layer "B.SilkS")
		)
		(fp_line
			(start -0.67945 -0.3048)
			(end -0.67945 0.3048)
			(stroke
				(width 0.1)
				(type default)
			)
			(layer "B.Fab")
		)
		(fp_line
			(start -0.67945 0.3048)
			(end -0.120396 0.3048)
			(stroke
				(width 0.1)
				(type default)
			)
			(layer "B.Fab")
		)
		(fp_line
			(start -0.12065 -0.3048)
			(end -0.67945 -0.3048)
			(stroke
				(width 0.1)
				(type default)
			)
			(layer "B.Fab")
		)
		(fp_line
			(start -0.12065 -0.2794)
			(end -0.12065 -0.3048)
			(stroke
				(width 0.1)
				(type default)
			)
			(layer "B.Fab")
		)
		(fp_line
			(start -0.120396 0.2794)
			(end 0.12065 0.2794)
			(stroke
				(width 0.1)
				(type default)
			)
			(layer "B.Fab")
		)
		(fp_line
			(start -0.120396 0.3048)
			(end -0.120396 0.2794)
			(stroke
				(width 0.1)
				(type default)
			)
			(layer "B.Fab")
		)
		(fp_line
			(start 0.12065 -0.305054)
			(end 0.12065 -0.2794)
			(stroke
				(width 0.1)
				(type default)
			)
			(layer "B.Fab")
		)
		(fp_line
			(start 0.12065 -0.2794)
			(end -0.12065 -0.2794)
			(stroke
				(width 0.1)
				(type default)
			)
			(layer "B.Fab")
		)
		(fp_line
			(start 0.12065 0.2794)
			(end 0.12065 0.3048)
			(stroke
				(width 0.1)
				(type default)
			)
			(layer "B.Fab")
		)
		(fp_line
			(start 0.12065 0.3048)
			(end 0.67945 0.3048)
			(stroke
				(width 0.1)
				(type default)
			)
			(layer "B.Fab")
		)
		(fp_line
			(start 0.67945 -0.305054)
			(end 0.12065 -0.305054)
			(stroke
				(width 0.1)
				(type default)
			)
			(layer "B.Fab")
		)
		(fp_line
			(start 0.67945 0.3048)
			(end 0.67945 -0.305054)
			(stroke
				(width 0.1)
				(type default)
			)
			(layer "B.Fab")
		)
		(pad "1" smd circle
			(at 0.40005 0 180)
			(size 0 0)
			(layers "B.Cu" "B.Mask" "B.Paste")
			(net "GND")
		)
		(pad "2" smd circle
			(at -0.40005 0 180)
			(size 0 0)
			(layers "B.Cu" "B.Mask" "B.Paste")
			(net "MB_HSC_EN")
		)
	)
	(footprint ""
		(layer "B.Cu")
		(at 296.980864 -457.31049 180)
		(property "Reference" "X74"
			(at 0.1778 -1.92913 180)
			(unlocked yes)
			(layer "B.SilkS")
			(effects
				(font
					(size 0.7874 0.5842)
					(thickness 0.1524)
				)
				(justify left mirror)
			)
		)
		(property "Value" ""
			(at 0 0 0)
			(layer "B.Fab")
			(effects
				(font
					(size 1.27 1.27)
				)
				(justify mirror)
			)
		)
		(property "Device Type" "TP_TDR_4P_FTS_MPKT4_H025P0200_IO_TP15_TP_TDR_4P_DIP"
			(at -1.30175 1.27 90)
			(unlocked yes)
			(layer "B.Fab")
			(hide yes)
			(effects
				(font
					(size 0.635 0.4064)
					(thickness 0.1524)
				)
				(justify mirror)
			)
		)
		(property "User Part Number" "TP15"
			(at -1.30175 1.27 90)
			(unlocked yes)
			(layer "Cmts.User")
			(hide yes)
			(effects
				(font
					(size 0.635 0.4064)
					(thickness 0.1524)
				)
				(justify mirror)
			)
		)
		(duplicate_pad_numbers_are_jumpers no)
		(fp_line
			(start 0 3.81)
			(end -2.54 3.81)
			(stroke
				(width 0.1524)
				(type default)
			)
			(layer "B.SilkS")
		)
		(fp_line
			(start 0 3.175)
			(end 0 3.81)
			(stroke
				(width 0.1524)
				(type default)
			)
			(layer "B.SilkS")
		)
		(fp_line
			(start 0 0.635)
			(end 0 1.905)
			(stroke
				(width 0.1524)
				(type default)
			)
			(layer "B.SilkS")
		)
		(fp_line
			(start 0 -1.27)
			(end 0 -0.635)
			(stroke
				(width 0.1524)
				(type default)
			)
			(layer "B.SilkS")
		)
		(fp_line
			(start -2.54 3.81)
			(end -2.54 3.6703)
			(stroke
				(width 0.1524)
				(type default)
			)
			(layer "B.SilkS")
		)
		(fp_line
			(start -2.54 1.4097)
			(end -2.54 1.1303)
			(stroke
				(width 0.1524)
				(type default)
			)
			(layer "B.SilkS")
		)
		(fp_line
			(start -2.54 -1.1303)
			(end -2.54 -1.27)
			(stroke
				(width 0.1524)
				(type default)
			)
			(layer "B.SilkS")
		)
		(fp_line
			(start -2.54 -1.27)
			(end 0 -1.27)
			(stroke
				(width 0.1524)
				(type default)
			)
			(layer "B.SilkS")
		)
		(fp_poly
			(pts
				(xy 0.761746 0) (xy 2.285746 -0.762) (xy 2.285746 0.762)
			)
			(stroke
				(width 0)
				(type default)
			)
			(fill yes)
			(layer "B.SilkS")
		)
		(fp_line
			(start 0 3.81)
			(end -2.54 3.81)
			(stroke
				(width 0.1)
				(type default)
			)
			(layer "B.Fab")
		)
		(fp_line
			(start 0 -1.27)
			(end 0 3.81)
			(stroke
				(width 0.1)
				(type default)
			)
			(layer "B.Fab")
		)
		(fp_line
			(start -2.54 3.81)
			(end -2.54 -1.27)
			(stroke
				(width 0.1)
				(type default)
			)
			(layer "B.Fab")
		)
		(fp_line
			(start -2.54 -1.27)
			(end 0 -1.27)
			(stroke
				(width 0.1)
				(type default)
			)
			(layer "B.Fab")
		)
		(fp_poly
			(pts
				(xy 0.761746 0) (xy 2.285746 -0.762) (xy 2.285746 0.762)
			)
			(stroke
				(width 0)
				(type default)
			)
			(fill yes)
			(layer "B.Fab")
		)
		(pad "1" thru_hole circle
			(at 0 0)
			(size 1.0033 1.0033)
			(drill 0.249936)
			(layers "*.Cu" "*.Mask")
			(remove_unused_layers no)
			(net "TDR_DIFF_100_IN4_DIP")
			(clearance 0.10795)
			(padstack
				(mode front_inner_back)
				(layer "Inner"
					(shape circle)
					(size 0.8001 0.8001)
					(clearance 0.1524)
				)
				(layer "B.Cu"
					(shape circle)
					(size 1.0033 1.0033)
					(thermal_gap 0.10795)
					(clearance 0.10795)
				)
			)
		)
		(pad "2" thru_hole circle
			(at -2.54 0)
			(size 1.9939 1.9939)
			(drill 0.249936)
			(layers "*.Cu" "*.Mask")
			(remove_unused_layers no)
			(net "COUPON_GND1")
			(clearance 0.10795)
			(padstack
				(mode front_inner_back)
				(layer "Inner"
					(shape circle)
					(size 0.8001 0.8001)
					(clearance 0.1524)
				)
				(layer "B.Cu"
					(shape circle)
					(size 1.9939 1.9939)
					(thermal_gap 0.10795)
					(clearance 0.10795)
				)
			)
		)
		(pad "3" thru_hole circle
			(at -2.54 2.54)
			(size 1.9939 1.9939)
			(drill 0.249936)
			(layers "*.Cu" "*.Mask")
			(remove_unused_layers no)
			(net "COUPON_GND1")
			(clearance 0.10795)
			(padstack
				(mode front_inner_back)
				(layer "Inner"
					(shape circle)
					(size 0.8001 0.8001)
					(clearance 0.1524)
				)
				(layer "B.Cu"
					(shape circle)
					(size 1.9939 1.9939)
					(thermal_gap 0.10795)
					(clearance 0.10795)
				)
			)
		)
		(pad "4" thru_hole circle
			(at 0 2.54)
			(size 1.0033 1.0033)
			(drill 0.249936)
			(layers "*.Cu" "*.Mask")
			(remove_unused_layers no)
			(net "TDR_DIFF_100_IN4_DIN")
			(clearance 0.10795)
			(padstack
				(mode front_inner_back)
				(layer "Inner"
					(shape circle)
					(size 0.8001 0.8001)
					(clearance 0.1524)
				)
				(layer "B.Cu"
					(shape circle)
					(size 1.0033 1.0033)
					(thermal_gap 0.10795)
					(clearance 0.10795)
				)
			)
		)
	)
	(footprint ""
		(layer "B.Cu")
		(at 180.975 -297.79976 -90)
		(property "Reference" "C1399"
			(at 0 0 90)
			(layer "B.SilkS")
			(hide yes)
			(effects
				(font
					(size 1.27 1.27)
				)
				(justify mirror)
			)
		)
		(property "Value" ""
			(at 0 0 90)
			(layer "B.Fab")
			(effects
				(font
					(size 1.27 1.27)
				)
				(justify mirror)
			)
		)
		(duplicate_pad_numbers_are_jumpers no)
		(fp_line
			(start -0.299974 0.150114)
			(end 0.299974 0.150114)
			(stroke
				(width 0.1)
				(type default)
			)
			(layer "B.Fab")
		)
		(fp_line
			(start 0.299974 0.150114)
			(end 0.299974 -0.150114)
			(stroke
				(width 0.1)
				(type default)
			)
			(layer "B.Fab")
		)
		(fp_line
			(start -0.299974 -0.150114)
			(end -0.299974 0.150114)
			(stroke
				(width 0.1)
				(type default)
			)
			(layer "B.Fab")
		)
		(fp_line
			(start 0.299974 -0.150114)
			(end -0.299974 -0.150114)
			(stroke
				(width 0.1)
				(type default)
			)
			(layer "B.Fab")
		)
		(pad "1" smd rect
			(at 0.2667 0 90)
			(size 0.3048 0.381)
			(layers "B.Cu" "B.Mask" "B.Paste")
			(net "P0V8_PEX1")
		)
		(pad "2" smd rect
			(at -0.2667 0 90)
			(size 0.3048 0.381)
			(layers "B.Cu" "B.Mask" "B.Paste")
			(net "GND")
		)
	)
	(footprint ""
		(layer "B.Cu")
		(at 187.149994 -297.32478 180)
		(property "Reference" "C3080"
			(at 0 0 0)
			(layer "B.SilkS")
			(hide yes)
			(effects
				(font
					(size 1.27 1.27)
				)
				(justify mirror)
			)
		)
		(property "Value" ""
			(at 0 0 0)
			(layer "B.Fab")
			(effects
				(font
					(size 1.27 1.27)
				)
				(justify mirror)
			)
		)
		(duplicate_pad_numbers_are_jumpers no)
		(fp_line
			(start 0.299974 0.150114)
			(end 0.299974 -0.150114)
			(stroke
				(width 0.1)
				(type default)
			)
			(layer "B.Fab")
		)
		(fp_line
			(start 0.299974 -0.150114)
			(end -0.299974 -0.150114)
			(stroke
				(width 0.1)
				(type default)
			)
			(layer "B.Fab")
		)
		(fp_line
			(start -0.299974 0.150114)
			(end 0.299974 0.150114)
			(stroke
				(width 0.1)
				(type default)
			)
			(layer "B.Fab")
		)
		(fp_line
			(start -0.299974 -0.150114)
			(end -0.299974 0.150114)
			(stroke
				(width 0.1)
				(type default)
			)
			(layer "B.Fab")
		)
		(pad "1" smd rect
			(at 0.2667 0)
			(size 0.3048 0.381)
			(layers "B.Cu" "B.Mask" "B.Paste")
			(net "P1V25_PEX1")
		)
		(pad "2" smd rect
			(at -0.2667 0)
			(size 0.3048 0.381)
			(layers "B.Cu" "B.Mask" "B.Paste")
			(net "GND")
		)
	)
	(footprint ""
		(layer "B.Cu")
		(at 377.910344 20.568412)
		(property "Reference" "DE06F_2"
			(at 2.480056 3.054858 0)
			(unlocked yes)
			(layer "B.SilkS")
			(effects
				(font
					(size 0.7874 0.5842)
					(thickness 0.1524)
				)
				(justify left mirror)
			)
		)
		(property "Value" ""
			(at 0 0 0)
			(layer "B.Fab")
			(effects
				(font
					(size 1.27 1.27)
				)
				(justify mirror)
			)
		)
		(duplicate_pad_numbers_are_jumpers no)
		(fp_line
			(start -1.2192 -2.1082)
			(end -1.2192 2.1082)
			(stroke
				(width 0.1524)
				(type default)
			)
			(layer "B.SilkS")
		)
		(fp_line
			(start -1.2192 2.1082)
			(end 1.2192 2.1082)
			(stroke
				(width 0.1524)
				(type default)
			)
			(layer "B.SilkS")
		)
		(fp_line
			(start 1.2192 -2.1082)
			(end -1.2192 -2.1082)
			(stroke
				(width 0.1524)
				(type default)
			)
			(layer "B.SilkS")
		)
		(fp_line
			(start 1.2192 2.1082)
			(end 1.2192 -2.1082)
			(stroke
				(width 0.1524)
				(type default)
			)
			(layer "B.SilkS")
		)
		(pad "" np_thru_hole circle
			(at -3.4671 -1.27 270)
			(size 1.0414 1.0414)
			(drill 1.0414)
			(layers "*.Cu" "*.Mask")
			(clearance 0.381)
			(thermal_gap 0.381)
		)
		(pad "" np_thru_hole circle
			(at -3.4671 1.27 270)
			(size 1.0414 1.0414)
			(drill 1.0414)
			(layers "*.Cu" "*.Mask")
			(clearance 0.381)
			(thermal_gap 0.381)
		)
		(pad "" np_thru_hole circle
			(at 2.8829 -1.27 270)
			(size 1.0414 1.0414)
			(drill 1.0414)
			(layers "*.Cu" "*.Mask")
			(clearance 0.381)
			(thermal_gap 0.381)
		)
		(pad "" np_thru_hole circle
			(at 2.8829 1.27 270)
			(size 1.0414 1.0414)
			(drill 1.0414)
			(layers "*.Cu" "*.Mask")
			(clearance 0.381)
			(thermal_gap 0.381)
		)
		(pad "1" smd rect
			(at -0.8255 -0.249936 270)
			(size 0.3048 0.508)
			(layers "B.Cu" "B.Mask" "B.Paste")
			(net "85_5INCH_IN4_DN")
		)
		(pad "2" smd rect
			(at -0.8255 0.249936 270)
			(size 0.3048 0.508)
			(layers "B.Cu" "B.Mask" "B.Paste")
			(net "85_5INCH_IN4_DP")
		)
		(pad "3" smd circle
			(at 0 0 180)
			(size 0 0)
			(layers "B.Cu" "B.Mask" "B.Paste")
			(net "COUPON_GND2")
		)
		(zone
			(layers "F.Cu" "B.Cu" "In1.Cu" "In2.Cu" "In3.Cu" "In4.Cu" "In5.Cu" "In6.Cu"
				"In7.Cu" "In8.Cu" "In9.Cu" "In10.Cu" "In11.Cu" "In12.Cu" "In13.Cu" "In14.Cu"
				"In15.Cu" "In16.Cu"
			)
			(hatch none 0.5)
			(connect_pads
				(clearance 0)
			)
			(min_thickness 0.25)
			(keepout
				(tracks not_allowed)
				(vias allowed)
				(pads allowed)
				(copperpour not_allowed)
				(footprints allowed)
			)
			(placement
				(enabled no)
				(sheetname "")
			)
			(fill
				(thermal_gap 0.5)
				(thermal_bridge_width 0.5)
				(island_removal_mode 0)
			)
			(polygon
				(pts
					(arc
						(start 375.370344 19.298412)
						(mid 373.516144 19.298412)
						(end 375.370344 19.298412)
					)
				)
			)
		)
		(zone
			(layers "F.Cu" "B.Cu" "In1.Cu" "In2.Cu" "In3.Cu" "In4.Cu" "In5.Cu" "In6.Cu"
				"In7.Cu" "In8.Cu" "In9.Cu" "In10.Cu" "In11.Cu" "In12.Cu" "In13.Cu" "In14.Cu"
				"In15.Cu" "In16.Cu"
			)
			(hatch none 0.5)
			(connect_pads
				(clearance 0)
			)
			(min_thickness 0.25)
			(keepout
				(tracks not_allowed)
				(vias allowed)
				(pads allowed)
				(copperpour not_allowed)
				(footprints allowed)
			)
			(placement
				(enabled no)
				(sheetname "")
			)
			(fill
				(thermal_gap 0.5)
				(thermal_bridge_width 0.5)
				(island_removal_mode 0)
			)
			(polygon
				(pts
					(arc
						(start 375.370344 21.838412)
						(mid 373.516144 21.838412)
						(end 375.370344 21.838412)
					)
				)
			)
		)
		(zone
			(layers "F.Cu" "B.Cu" "In1.Cu" "In2.Cu" "In3.Cu" "In4.Cu" "In5.Cu" "In6.Cu"
				"In7.Cu" "In8.Cu" "In9.Cu" "In10.Cu" "In11.Cu" "In12.Cu" "In13.Cu" "In14.Cu"
				"In15.Cu" "In16.Cu"
			)
			(hatch none 0.5)
			(connect_pads
				(clearance 0)
			)
			(min_thickness 0.25)
			(keepout
				(tracks not_allowed)
				(vias allowed)
				(pads allowed)
				(copperpour not_allowed)
				(footprints allowed)
			)
			(placement
				(enabled no)
				(sheetname "")
			)
			(fill
				(thermal_gap 0.5)
				(thermal_bridge_width 0.5)
				(island_removal_mode 0)
			)
			(polygon
				(pts
					(arc
						(start 381.720344 19.298412)
						(mid 379.866144 19.298412)
						(end 381.720344 19.298412)
					)
				)
			)
		)
		(zone
			(layers "F.Cu" "B.Cu" "In1.Cu" "In2.Cu" "In3.Cu" "In4.Cu" "In5.Cu" "In6.Cu"
				"In7.Cu" "In8.Cu" "In9.Cu" "In10.Cu" "In11.Cu" "In12.Cu" "In13.Cu" "In14.Cu"
				"In15.Cu" "In16.Cu"
			)
			(hatch none 0.5)
			(connect_pads
				(clearance 0)
			)
			(min_thickness 0.25)
			(keepout
				(tracks not_allowed)
				(vias allowed)
				(pads allowed)
				(copperpour not_allowed)
				(footprints allowed)
			)
			(placement
				(enabled no)
				(sheetname "")
			)
			(fill
				(thermal_gap 0.5)
				(thermal_bridge_width 0.5)
				(island_removal_mode 0)
			)
			(polygon
				(pts
					(arc
						(start 381.720344 21.838412)
						(mid 379.866144 21.838412)
						(end 381.720344 21.838412)
					)
				)
			)
		)
		(zone
			(layer "B.Cu")
			(hatch none 0.5)
			(connect_pads
				(clearance 0)
			)
			(min_thickness 0.25)
			(keepout
				(tracks not_allowed)
				(vias allowed)
				(pads allowed)
				(copperpour not_allowed)
				(footprints allowed)
			)
			(placement
				(enabled no)
				(sheetname "")
			)
			(fill
				(thermal_gap 0.5)
				(thermal_bridge_width 0.5)
				(island_removal_mode 0)
			)
			(polygon
				(pts
					(xy 376.792744 20.019772) (xy 376.792744 20.115276) (xy 377.389644 20.115276) (xy 377.389644 20.521676)
					(xy 376.792744 20.521676) (xy 376.792744 20.615148) (xy 377.389644 20.615148) (xy 377.389644 21.021548)
					(xy 376.792744 21.021548) (xy 376.792744 21.117052) (xy 377.491244 21.117052) (xy 377.491244 20.019772)
				)
			)
		)
	)
)
